(kicad_pcb
	(version 20260206)
	(generator "pcbnew")
	(generator_version "10.0")
	(general
		(thickness 1.6)
		(legacy_teardrops no)
	)
	(paper "A4")
	(title_block
		(title "04192023_DAF0TMB3IC0_F0TG_MB_C_brd_V02_OCP.brd")
		(comment 1 "Grand Teton / footprints 1553-1560 of 8354")
	)
	(layers
		(0 "F.Cu" signal "TOP")
		(4 "In1.Cu" signal "GND")
		(6 "In2.Cu" signal "IN1")
		(8 "In3.Cu" signal "GND1")
		(10 "In4.Cu" signal "IN2")
		(12 "In5.Cu" signal "GND2")
		(14 "In6.Cu" signal "IN3")
		(16 "In7.Cu" signal "GND3")
		(18 "In8.Cu" signal "VCC")
		(20 "In9.Cu" signal "VCC1")
		(22 "In10.Cu" signal "GND4")
		(24 "In11.Cu" signal "IN4")
		(26 "In12.Cu" signal "GND5")
		(28 "In13.Cu" signal "IN5")
		(30 "In14.Cu" signal "GND6")
		(32 "In15.Cu" signal "IN6")
		(34 "In16.Cu" signal "GND7")
		(2 "B.Cu" signal "BOTTOM")
		(9 "F.Adhes" user "F.Adhesive")
		(11 "B.Adhes" user "B.Adhesive")
		(13 "F.Paste" user "Package Geometry/Pastemask Top")
		(15 "B.Paste" user "Package Geometry/Pastemask Bottom")
		(5 "F.SilkS" user "Ref Des/Silkscreen Top")
		(7 "B.SilkS" user "Ref Des/Silkscreen Bottom")
		(1 "F.Mask" user "Board Geometry/Soldermask Top")
		(3 "B.Mask" user "Board Geometry/Soldermask Bottom")
		(17 "Dwgs.User" user "User.Drawings")
		(19 "Cmts.User" user "User.Comments")
		(21 "Eco1.User" user "User.Eco1")
		(23 "Eco2.User" user "User.Eco2")
		(25 "Edge.Cuts" user "Board Geometry/Outline")
		(27 "Margin" user)
		(31 "F.CrtYd" user "Package Geometry/Place Bound Top")
		(29 "B.CrtYd" user "Package Geometry/Place Bound Bottom")
		(35 "F.Fab" user "Ref Des/Assembly Top")
		(33 "B.Fab" user "Ref Des/Assembly Bottom")
	)
	(footprint ""
		(layer "F.Cu")
		(at 10.066782 -410.818584 180)
		(property "Reference" "PC523"
			(at 0 0 180)
			(layer "F.SilkS")
			(hide yes)
			(effects
				(font
					(size 1.27 1.27)
				)
			)
		)
		(property "Value" ""
			(at 0 0 180)
			(layer "F.Fab")
			(effects
				(font
					(size 1.27 1.27)
				)
			)
		)
		(duplicate_pad_numbers_are_jumpers no)
		(fp_line
			(start 0.7874 0.4064)
			(end -0.7874 0.4064)
			(stroke
				(width 0.1524)
				(type default)
			)
			(layer "F.SilkS")
		)
		(fp_line
			(start 0.7874 -0.4064)
			(end 0.7874 0.4064)
			(stroke
				(width 0.1524)
				(type default)
			)
			(layer "F.SilkS")
		)
		(fp_line
			(start -0.7874 0.4064)
			(end -0.7874 -0.4064)
			(stroke
				(width 0.1524)
				(type default)
			)
			(layer "F.SilkS")
		)
		(fp_line
			(start -0.7874 -0.4064)
			(end 0.7874 -0.4064)
			(stroke
				(width 0.1524)
				(type default)
			)
			(layer "F.SilkS")
		)
		(fp_line
			(start 0.67945 0.3048)
			(end 0.120396 0.3048)
			(stroke
				(width 0.1)
				(type default)
			)
			(layer "F.Fab")
		)
		(fp_line
			(start 0.67945 -0.3048)
			(end 0.67945 0.3048)
			(stroke
				(width 0.1)
				(type default)
			)
			(layer "F.Fab")
		)
		(fp_line
			(start 0.12065 -0.2794)
			(end 0.12065 -0.3048)
			(stroke
				(width 0.1)
				(type default)
			)
			(layer "F.Fab")
		)
		(fp_line
			(start 0.12065 -0.3048)
			(end 0.67945 -0.3048)
			(stroke
				(width 0.1)
				(type default)
			)
			(layer "F.Fab")
		)
		(fp_line
			(start 0.120396 0.3048)
			(end 0.120396 0.2794)
			(stroke
				(width 0.1)
				(type default)
			)
			(layer "F.Fab")
		)
		(fp_line
			(start 0.120396 0.2794)
			(end -0.12065 0.2794)
			(stroke
				(width 0.1)
				(type default)
			)
			(layer "F.Fab")
		)
		(fp_line
			(start -0.12065 0.3048)
			(end -0.67945 0.3048)
			(stroke
				(width 0.1)
				(type default)
			)
			(layer "F.Fab")
		)
		(fp_line
			(start -0.12065 0.2794)
			(end -0.12065 0.3048)
			(stroke
				(width 0.1)
				(type default)
			)
			(layer "F.Fab")
		)
		(fp_line
			(start -0.12065 -0.2794)
			(end 0.12065 -0.2794)
			(stroke
				(width 0.1)
				(type default)
			)
			(layer "F.Fab")
		)
		(fp_line
			(start -0.12065 -0.305054)
			(end -0.12065 -0.2794)
			(stroke
				(width 0.1)
				(type default)
			)
			(layer "F.Fab")
		)
		(fp_line
			(start -0.67945 0.3048)
			(end -0.67945 -0.305054)
			(stroke
				(width 0.1)
				(type default)
			)
			(layer "F.Fab")
		)
		(fp_line
			(start -0.67945 -0.305054)
			(end -0.12065 -0.305054)
			(stroke
				(width 0.1)
				(type default)
			)
			(layer "F.Fab")
		)
		(pad "1" smd circle
			(at -0.40005 0 180)
			(size 0 0)
			(layers "F.Cu" "F.Mask" "F.Paste")
			(net "P0V9_RETIMER_CPU1_TEMP0")
		)
		(pad "2" smd circle
			(at 0.40005 0 180)
			(size 0 0)
			(layers "F.Cu" "F.Mask" "F.Paste")
			(net "GND")
		)
	)
	(footprint ""
		(layer "F.Cu")
		(at 414.331912 -364.781592 180)
		(property "Reference" "C196"
			(at 0 0 180)
			(layer "F.SilkS")
			(hide yes)
			(effects
				(font
					(size 1.27 1.27)
				)
			)
		)
		(property "Value" ""
			(at 0 0 180)
			(layer "F.Fab")
			(effects
				(font
					(size 1.27 1.27)
				)
			)
		)
		(duplicate_pad_numbers_are_jumpers no)
		(fp_line
			(start 0.7874 0.4064)
			(end -0.7874 0.4064)
			(stroke
				(width 0.1524)
				(type default)
			)
			(layer "F.SilkS")
		)
		(fp_line
			(start 0.7874 -0.4064)
			(end 0.7874 0.4064)
			(stroke
				(width 0.1524)
				(type default)
			)
			(layer "F.SilkS")
		)
		(fp_line
			(start -0.7874 0.4064)
			(end -0.7874 -0.4064)
			(stroke
				(width 0.1524)
				(type default)
			)
			(layer "F.SilkS")
		)
		(fp_line
			(start -0.7874 -0.4064)
			(end 0.7874 -0.4064)
			(stroke
				(width 0.1524)
				(type default)
			)
			(layer "F.SilkS")
		)
		(fp_line
			(start 0.67945 0.3048)
			(end 0.120396 0.3048)
			(stroke
				(width 0.1)
				(type default)
			)
			(layer "F.Fab")
		)
		(fp_line
			(start 0.67945 -0.3048)
			(end 0.67945 0.3048)
			(stroke
				(width 0.1)
				(type default)
			)
			(layer "F.Fab")
		)
		(fp_line
			(start 0.12065 -0.2794)
			(end 0.12065 -0.3048)
			(stroke
				(width 0.1)
				(type default)
			)
			(layer "F.Fab")
		)
		(fp_line
			(start 0.12065 -0.3048)
			(end 0.67945 -0.3048)
			(stroke
				(width 0.1)
				(type default)
			)
			(layer "F.Fab")
		)
		(fp_line
			(start 0.120396 0.3048)
			(end 0.120396 0.2794)
			(stroke
				(width 0.1)
				(type default)
			)
			(layer "F.Fab")
		)
		(fp_line
			(start 0.120396 0.2794)
			(end -0.12065 0.2794)
			(stroke
				(width 0.1)
				(type default)
			)
			(layer "F.Fab")
		)
		(fp_line
			(start -0.12065 0.3048)
			(end -0.67945 0.3048)
			(stroke
				(width 0.1)
				(type default)
			)
			(layer "F.Fab")
		)
		(fp_line
			(start -0.12065 0.2794)
			(end -0.12065 0.3048)
			(stroke
				(width 0.1)
				(type default)
			)
			(layer "F.Fab")
		)
		(fp_line
			(start -0.12065 -0.2794)
			(end 0.12065 -0.2794)
			(stroke
				(width 0.1)
				(type default)
			)
			(layer "F.Fab")
		)
		(fp_line
			(start -0.12065 -0.305054)
			(end -0.12065 -0.2794)
			(stroke
				(width 0.1)
				(type default)
			)
			(layer "F.Fab")
		)
		(fp_line
			(start -0.67945 0.3048)
			(end -0.67945 -0.305054)
			(stroke
				(width 0.1)
				(type default)
			)
			(layer "F.Fab")
		)
		(fp_line
			(start -0.67945 -0.305054)
			(end -0.12065 -0.305054)
			(stroke
				(width 0.1)
				(type default)
			)
			(layer "F.Fab")
		)
		(pad "1" smd circle
			(at -0.40005 0 180)
			(size 0 0)
			(layers "F.Cu" "F.Mask" "F.Paste")
			(net "PWRGD_PVDD11_S3_P0_R")
		)
		(pad "2" smd circle
			(at 0.40005 0 180)
			(size 0 0)
			(layers "F.Cu" "F.Mask" "F.Paste")
			(net "GND")
		)
	)
	(footprint ""
		(layer "F.Cu")
		(at 336.827876 -70.098412 90)
		(property "Reference" "D80"
			(at -3.934714 -0.691642 90)
			(unlocked yes)
			(layer "F.SilkS")
			(effects
				(font
					(size 0.7874 0.5842)
					(thickness 0.1524)
				)
				(justify left)
			)
		)
		(property "Value" ""
			(at 0 0 90)
			(layer "F.Fab")
			(effects
				(font
					(size 1.27 1.27)
				)
			)
		)
		(duplicate_pad_numbers_are_jumpers no)
		(fp_line
			(start 1.16078 -0.4826)
			(end 1.16078 0.4826)
			(stroke
				(width 0.1524)
				(type default)
			)
			(layer "F.SilkS")
		)
		(fp_line
			(start 1.03378 -0.4826)
			(end 1.03378 0.4826)
			(stroke
				(width 0.1524)
				(type default)
			)
			(layer "F.SilkS")
		)
		(fp_line
			(start 0.90678 -0.4826)
			(end 0.90678 0.4826)
			(stroke
				(width 0.1524)
				(type default)
			)
			(layer "F.SilkS")
		)
		(fp_line
			(start -0.64008 -0.4826)
			(end 1.16078 -0.4826)
			(stroke
				(width 0.1524)
				(type default)
			)
			(layer "F.SilkS")
		)
		(fp_line
			(start -0.79248 -0.4826)
			(end 1.03378 -0.4826)
			(stroke
				(width 0.1524)
				(type default)
			)
			(layer "F.SilkS")
		)
		(fp_line
			(start -0.89408 -0.4826)
			(end 0.90678 -0.4826)
			(stroke
				(width 0.1524)
				(type default)
			)
			(layer "F.SilkS")
		)
		(fp_line
			(start 1.16078 0.4826)
			(end -0.64008 0.4826)
			(stroke
				(width 0.1524)
				(type default)
			)
			(layer "F.SilkS")
		)
		(fp_line
			(start 1.03378 0.4826)
			(end -0.79248 0.4826)
			(stroke
				(width 0.1524)
				(type default)
			)
			(layer "F.SilkS")
		)
		(fp_line
			(start 0.90678 0.4826)
			(end -0.90678 0.4826)
			(stroke
				(width 0.1524)
				(type default)
			)
			(layer "F.SilkS")
		)
		(fp_line
			(start -0.90678 0.4826)
			(end -0.90678 -0.4699)
			(stroke
				(width 0.1524)
				(type default)
			)
			(layer "F.SilkS")
		)
		(fp_line
			(start 0.499872 -0.249936)
			(end 0.499872 0.249936)
			(stroke
				(width 0.1)
				(type default)
			)
			(layer "F.Fab")
		)
		(fp_line
			(start -0.499872 -0.249936)
			(end 0.499872 -0.249936)
			(stroke
				(width 0.1)
				(type default)
			)
			(layer "F.Fab")
		)
		(fp_line
			(start 0.499872 0.249936)
			(end -0.499872 0.249936)
			(stroke
				(width 0.1)
				(type default)
			)
			(layer "F.Fab")
		)
		(fp_line
			(start -0.499872 0.249936)
			(end -0.499872 -0.249936)
			(stroke
				(width 0.1)
				(type default)
			)
			(layer "F.Fab")
		)
		(pad "A" smd rect
			(at -0.47498 0 90)
			(size 0.6096 0.7112)
			(layers "F.Cu" "F.Mask" "F.Paste")
			(net "LED_PWRGD_PVDDCR_CPU0_P1_R")
		)
		(pad "C" smd rect
			(at 0.47498 0 90)
			(size 0.6096 0.7112)
			(layers "F.Cu" "F.Mask" "F.Paste")
			(net "LED_PWRGD_PVDDCR_CPU0_P1_D")
		)
	)
	(footprint ""
		(layer "F.Cu")
		(at 392.801348 -17.624298 90)
		(property "Reference" "C1550"
			(at 0 0 90)
			(layer "F.SilkS")
			(hide yes)
			(effects
				(font
					(size 1.27 1.27)
				)
			)
		)
		(property "Value" ""
			(at 0 0 90)
			(layer "F.Fab")
			(effects
				(font
					(size 1.27 1.27)
				)
			)
		)
		(duplicate_pad_numbers_are_jumpers no)
		(fp_line
			(start 0.299974 -0.150114)
			(end 0.299974 0.150114)
			(stroke
				(width 0.1)
				(type default)
			)
			(layer "F.Fab")
		)
		(fp_line
			(start -0.299974 -0.150114)
			(end 0.299974 -0.150114)
			(stroke
				(width 0.1)
				(type default)
			)
			(layer "F.Fab")
		)
		(fp_line
			(start 0.299974 0.150114)
			(end -0.299974 0.150114)
			(stroke
				(width 0.1)
				(type default)
			)
			(layer "F.Fab")
		)
		(fp_line
			(start -0.299974 0.150114)
			(end -0.299974 -0.150114)
			(stroke
				(width 0.1)
				(type default)
			)
			(layer "F.Fab")
		)
		(pad "1" smd rect
			(at -0.2667 0 90)
			(size 0.3048 0.381)
			(layers "F.Cu" "F.Mask" "F.Paste")
			(net "P5E_CPU0_G3_TX_C_DN<14>")
		)
		(pad "2" smd rect
			(at 0.2667 0 90)
			(size 0.3048 0.381)
			(layers "F.Cu" "F.Mask" "F.Paste")
			(net "P5E_CPU0_G3_TX_DN<14>")
		)
	)
	(footprint ""
		(layer "F.Cu")
		(at 107.722924 -392.521694)
		(property "Reference" "L10"
			(at -4.85648 -0.739648 0)
			(unlocked yes)
			(layer "F.SilkS")
			(effects
				(font
					(size 0.7874 0.5842)
					(thickness 0.1524)
				)
				(justify left)
			)
		)
		(property "Value" ""
			(at 0 0 0)
			(layer "F.Fab")
			(effects
				(font
					(size 1.27 1.27)
				)
			)
		)
		(duplicate_pad_numbers_are_jumpers no)
		(fp_line
			(start -2.249932 -2.249932)
			(end 2.249932 -2.249932)
			(stroke
				(width 0.1524)
				(type default)
			)
			(layer "F.SilkS")
		)
		(fp_line
			(start -2.249932 -1.3843)
			(end -2.249932 -2.249932)
			(stroke
				(width 0.1524)
				(type default)
			)
			(layer "F.SilkS")
		)
		(fp_line
			(start -2.249932 2.249932)
			(end -2.249932 1.3843)
			(stroke
				(width 0.1524)
				(type default)
			)
			(layer "F.SilkS")
		)
		(fp_line
			(start 2.249932 -2.249932)
			(end 2.249932 -1.3843)
			(stroke
				(width 0.1524)
				(type default)
			)
			(layer "F.SilkS")
		)
		(fp_line
			(start 2.249932 1.3843)
			(end 2.249932 2.249932)
			(stroke
				(width 0.1524)
				(type default)
			)
			(layer "F.SilkS")
		)
		(fp_line
			(start 2.249932 2.249932)
			(end -2.249932 2.249932)
			(stroke
				(width 0.1524)
				(type default)
			)
			(layer "F.SilkS")
		)
		(fp_line
			(start -2.249932 -2.249932)
			(end 2.249932 -2.249932)
			(stroke
				(width 0.1)
				(type default)
			)
			(layer "F.Fab")
		)
		(fp_line
			(start -2.249932 2.249932)
			(end -2.249932 -2.249932)
			(stroke
				(width 0.1)
				(type default)
			)
			(layer "F.Fab")
		)
		(fp_line
			(start 2.249932 -2.249932)
			(end 2.249932 2.249932)
			(stroke
				(width 0.1)
				(type default)
			)
			(layer "F.Fab")
		)
		(fp_line
			(start 2.249932 2.249932)
			(end -2.249932 2.249932)
			(stroke
				(width 0.1)
				(type default)
			)
			(layer "F.Fab")
		)
		(pad "1" smd rect
			(at -1.82499 0)
			(size 1.0668 2.5146)
			(layers "F.Cu" "F.Mask" "F.Paste")
			(net "P0V9_CPU1_RT_2D")
		)
		(pad "2" smd rect
			(at 1.82499 0)
			(size 1.0668 2.5146)
			(layers "F.Cu" "F.Mask" "F.Paste")
			(net "P0V9_CPU1_RT3_2A")
		)
	)
	(footprint ""
		(layer "F.Cu")
		(at 398.155668 -396.146274)
		(property "Reference" "R613"
			(at 0 0 0)
			(layer "F.SilkS")
			(hide yes)
			(effects
				(font
					(size 1.27 1.27)
				)
			)
		)
		(property "Value" ""
			(at 0 0 0)
			(layer "F.Fab")
			(effects
				(font
					(size 1.27 1.27)
				)
			)
		)
		(duplicate_pad_numbers_are_jumpers no)
		(fp_line
			(start -0.32512 -0.175006)
			(end 0.32512 -0.175006)
			(stroke
				(width 0.1)
				(type default)
			)
			(layer "F.Fab")
		)
		(fp_line
			(start -0.32512 0.175006)
			(end -0.32512 -0.175006)
			(stroke
				(width 0.1)
				(type default)
			)
			(layer "F.Fab")
		)
		(fp_line
			(start 0.32512 -0.175006)
			(end 0.32512 0.175006)
			(stroke
				(width 0.1)
				(type default)
			)
			(layer "F.Fab")
		)
		(fp_line
			(start 0.32512 0.175006)
			(end -0.32512 0.175006)
			(stroke
				(width 0.1)
				(type default)
			)
			(layer "F.Fab")
		)
		(pad "1" smd rect
			(at -0.2667 0)
			(size 0.3048 0.381)
			(layers "F.Cu" "F.Mask" "F.Paste")
			(net "CLK_100M_RETIMER_CPU0_P2_R_DP")
		)
		(pad "2" smd rect
			(at 0.2667 0 180)
			(size 0.3048 0.381)
			(layers "F.Cu" "F.Mask" "F.Paste")
			(net "CLK_100M_RETIMER_CPU0_P2_DP")
		)
	)
	(footprint ""
		(layer "F.Cu")
		(at 75.337924 -408.517344 -90)
		(property "Reference" "C6648"
			(at 0 0 270)
			(layer "F.SilkS")
			(hide yes)
			(effects
				(font
					(size 1.27 1.27)
				)
			)
		)
		(property "Value" ""
			(at 0 0 270)
			(layer "F.Fab")
			(effects
				(font
					(size 1.27 1.27)
				)
			)
		)
		(duplicate_pad_numbers_are_jumpers no)
		(fp_line
			(start -0.299974 0.150114)
			(end -0.299974 -0.150114)
			(stroke
				(width 0.1)
				(type default)
			)
			(layer "F.Fab")
		)
		(fp_line
			(start 0.299974 0.150114)
			(end -0.299974 0.150114)
			(stroke
				(width 0.1)
				(type default)
			)
			(layer "F.Fab")
		)
		(fp_line
			(start -0.299974 -0.150114)
			(end 0.299974 -0.150114)
			(stroke
				(width 0.1)
				(type default)
			)
			(layer "F.Fab")
		)
		(fp_line
			(start 0.299974 -0.150114)
			(end 0.299974 0.150114)
			(stroke
				(width 0.1)
				(type default)
			)
			(layer "F.Fab")
		)
		(pad "1" smd rect
			(at -0.2667 0 270)
			(size 0.3048 0.381)
			(layers "F.Cu" "F.Mask" "F.Paste")
			(net "P5E_CPU1_P0_TX_BUF_C_DN<9>")
		)
		(pad "2" smd rect
			(at 0.2667 0 270)
			(size 0.3048 0.381)
			(layers "F.Cu" "F.Mask" "F.Paste")
			(net "P5E_CPU1_P0_TX_BUF_DN<9>")
		)
	)
	(footprint ""
		(layer "F.Cu")
		(at 189.941962 -356.532434 180)
		(property "Reference" "PR329"
			(at 0 0 180)
			(layer "F.SilkS")
			(hide yes)
			(effects
				(font
					(size 1.27 1.27)
				)
			)
		)
		(property "Value" ""
			(at 0 0 180)
			(layer "F.Fab")
			(effects
				(font
					(size 1.27 1.27)
				)
			)
		)
		(duplicate_pad_numbers_are_jumpers no)
		(fp_line
			(start 0.7874 0.4064)
			(end -0.7874 0.4064)
			(stroke
				(width 0.1524)
				(type default)
			)
			(layer "F.SilkS")
		)
		(fp_line
			(start 0.7874 -0.4064)
			(end 0.7874 0.4064)
			(stroke
				(width 0.1524)
				(type default)
			)
			(layer "F.SilkS")
		)
		(fp_line
			(start -0.7874 0.4064)
			(end -0.7874 -0.4064)
			(stroke
				(width 0.1524)
				(type default)
			)
			(layer "F.SilkS")
		)
		(fp_line
			(start -0.7874 -0.4064)
			(end 0.7874 -0.4064)
			(stroke
				(width 0.1524)
				(type default)
			)
			(layer "F.SilkS")
		)
		(fp_line
			(start 0.67945 0.3048)
			(end 0.120396 0.3048)
			(stroke
				(width 0.1)
				(type default)
			)
			(layer "F.Fab")
		)
		(fp_line
			(start 0.67945 -0.3048)
			(end 0.67945 0.3048)
			(stroke
				(width 0.1)
				(type default)
			)
			(layer "F.Fab")
		)
		(fp_line
			(start 0.12065 -0.2794)
			(end 0.12065 -0.3048)
			(stroke
				(width 0.1)
				(type default)
			)
			(layer "F.Fab")
		)
		(fp_line
			(start 0.12065 -0.3048)
			(end 0.67945 -0.3048)
			(stroke
				(width 0.1)
				(type default)
			)
			(layer "F.Fab")
		)
		(fp_line
			(start 0.120396 0.3048)
			(end 0.120396 0.2794)
			(stroke
				(width 0.1)
				(type default)
			)
			(layer "F.Fab")
		)
		(fp_line
			(start 0.120396 0.2794)
			(end -0.12065 0.2794)
			(stroke
				(width 0.1)
				(type default)
			)
			(layer "F.Fab")
		)
		(fp_line
			(start -0.12065 0.3048)
			(end -0.67945 0.3048)
			(stroke
				(width 0.1)
				(type default)
			)
			(layer "F.Fab")
		)
		(fp_line
			(start -0.12065 0.2794)
			(end -0.12065 0.3048)
			(stroke
				(width 0.1)
				(type default)
			)
			(layer "F.Fab")
		)
		(fp_line
			(start -0.12065 -0.2794)
			(end 0.12065 -0.2794)
			(stroke
				(width 0.1)
				(type default)
			)
			(layer "F.Fab")
		)
		(fp_line
			(start -0.12065 -0.305054)
			(end -0.12065 -0.2794)
			(stroke
				(width 0.1)
				(type default)
			)
			(layer "F.Fab")
		)
		(fp_line
			(start -0.67945 0.3048)
			(end -0.67945 -0.305054)
			(stroke
				(width 0.1)
				(type default)
			)
			(layer "F.Fab")
		)
		(fp_line
			(start -0.67945 -0.305054)
			(end -0.12065 -0.305054)
			(stroke
				(width 0.1)
				(type default)
			)
			(layer "F.Fab")
		)
		(pad "1" smd circle
			(at -0.40005 0 180)
			(size 0 0)
			(layers "F.Cu" "F.Mask" "F.Paste")
			(net "GND")
		)
		(pad "2" smd circle
			(at 0.40005 0 180)
			(size 0 0)
			(layers "F.Cu" "F.Mask" "F.Paste")
			(net "PVDD11_S3_P1_LSET2")
		)
	)
)
